FILE_TYPE = CONNECTIVITY;
{Allegro Design Entry HDL 17.2-2016 S081 (4005846) 1/11/2022}
"PAGE_NUMBER" = 111;
0"NC";
1"GND\g";
2"GND\g";
3"GND\g";
4"P3V3\g";
5"GND\g";
6"GND\g";
7"PVDD11_S3_P0\g";
8"GND\g";
9"GND\g";
10"GND\g";
11"GND\g";
12"GND\g";
13"GND\g";
14"GND\g";
15"GND\g";
16"GND\g";
17"P3V3\g";
18"GND\g";
19"GND\g";
20"P3V3\g";
21"PWRGD_PVDD11_S3_P0_R_N";
22"P3V3\g";
23"P3V3\g";
24"GND\g";
25"PVDD11_S3_P0\g";
26"PVDD11_S3_P0\g";
27"P3V3_9ZX_VDDA_2\g";
28"P3V3_9ZX_VDD_2\g";
29"P3V3_9ZX_VDDA_2\g";
30"P3V3_9ZX_VDDA_2\g";
31"P3V3_9ZX_VDD_2\g";
32"P3V3\g";
33"SMB_CPU0_2_SCL";
34"SMB_CPU0_2_SDA";
35"SMB_CPU0_3_SCL";
36"SMB_CPU0_3_SDA";
37"SMB_CPU0_3_XLTR_SCL";
38"PWRGD_PVDD11_S3_P0_R_N";
39"PWRGD_PVDD11_S3_P0_N";
40"PWRGD_PVDD11_S3_P0";
41"FM_CLK_BUFFER2_EN_R";
42"CLK_100M_CPU1_CLK15_DP";
43"CLK_100M_OCP_DP";
44"CLK_100M_OCP_DN";
45"CLK_100M_SLOT3_R_DP";
46"FM_CLK_100M_SLOT3_OE_N_R";
47"SMB_CPU0_3_XLTR_SCL";
48"SMB_CPU0_3_XLTR_SDA";
49"SMB_CPU0_2_XLTR_SCL";
50"SADR_2";
51"FM_CLK_BUFFER2_EN";
52"FM_CLK_BUFFER2_EN";
53"SMB_CPU0_3_XLTR_SCL";
54"SMB_CPU0_3_XLTR_SDA";
55"SMB_CLK_BUF2_SCL";
56"SMB_CLK_BUF2_SDA";
57"CLK_100M_CPU1_CLK15_DN";
58"SADR_2";
59"SMB_CPU0_2_XLTR_SCL";
60"SMB_CPU0_2_XLTR_SDA";
61"SMB_CPU0_3_XLTR_SDA";
62"SMB_CPU0_2_XLTR_SDA";
63"SMB_CPU0_2_SDA";
64"SMB_CPU0_3_SCL";
65"SMB_CPU0_2_SCL";
66"SMB_CPU0_3_SDA";
67"CLKBUF2_PLL_MODE";
68"CLK_100M_SLOT3_R_DN";
69"CLK_100M_OCP_R_DN";
70"CLK_100M_OCP_R_DP";
71"FM_CLK_100M_OCP_OE_N_R";
72"FM_CLK_100M_SLOT3_OE_N";
73"FM_CLK_100M_OCP_OE_N";
74"CLK_100M_SLOT3_DP";
75"CLK_100M_SLOT3_DN";
76"GND\g";
%"9ZXL0451EKILFT"
"1","(-3375,5000)","0","pure_quanta","I1";
;
LOCATION"U70"
$SEC"1"
CDS_SEC"1"
PART_NUMBER"AL000451003"
VALUE"9ZXL0451EKILFT"
MATERIAL"IC"
PART_TYPE"SMLF"
CDS_LIB"pure_quanta"
CDS_LMAN_SYM_OUTLINE"-475,725,475,-725"
NEEDS_NO_SIZE"TRUE";
"VSADR0_TRI"
$PN"5"58;
"NC2"
$PN"17"0;
"NC3"
$PN"30"0;
"VDD0"
$PN"12"28;
"DIF3"
$PN"27"0;
"DIF1"
$PN"19"70;
"EPAD_GND"
$PN"33"18;
"^HIBW_BYPM_LOBW# \B"
$PN"32"67;
"VDD1"
$PN"16"28;
"VDDA"
$PN"31"29;
"NC0"
$PN"10"0;
"DIF3# \B"
$PN"28"0;
"DIF2# \B"
$PN"23"0;
"VOE2# \B"
$PN"24"0;
"DIF2"
$PN"22"0;
"DIF1# \B"
$PN"20"69;
"VOE1# \B"
$PN"18"71;
"DIF0"
$PN"13"45;
"DIF0# \B"
$PN"14"68;
"^CKPWRGD_PD# \B"
$PN"1"41;
"VDD2"
$PN"21"28;
"SMBCLK"
$PN"7"55;
"FBOUT_NC# \B"
$PN"8"0;
"NC1"
$PN"11"0;
"SMBDAT"
$PN"6"56;
"VOE3# \B"
$PN"26"0;
"VOE0# \B"
$PN"15"46;
"FBOUT_NC"
$PN"9"0;
"VDD4"
$PN"29"28;
"VDD3"
$PN"25"28;
"VDDR"
$PN"2"27;
"DIF_IN# \B"
$PN"4"57;
"DIF_IN"
$PN"3"42;
%"UNIVERSAL_POWER"
"1","(-1800,1825)","0","pure_quanta_power","I104";
;
HDL_POWER"P3V3"
CDS_LIB"pure_quanta_power";
"A"22;
%"UNIVERSAL_GND"
"1","(-1675,1375)","2","pure_quanta_power","I105";
;
HDL_POWER"GND"
CDS_LIB"pure_quanta_power";
"A"1;
%"Q_CAP"
"1","(-1675,1575)","0","pure_quanta","I106";
;
LOCATION"C32"
$SEC"1"
CDS_SEC"1"
PACK_TYPE"0402"
VOLTAGE"25V"
PART_NUMBER"CH4104K1B00"
VALUE"0.1UF"
TOLERANCE"10%"
MATERIAL"X7R"
CDS_LIB"pure_quanta";
"B"
$PN"2"1;
"A"
$PN"1"22;
%"UNIVERSAL_GND"
"1","(-1775,775)","2","pure_quanta_power","I107";
;
HDL_POWER"GND"
CDS_LIB"pure_quanta_power";
"A"2;
%"UNIVERSAL_GND"
"1","(-3000,1375)","0","pure_quanta_power","I109";
;
HDL_POWER"GND"
CDS_LIB"pure_quanta_power";
"A"3;
%"Q_CAP"
"1","(-3000,1575)","2","pure_quanta","I110";
;
LOCATION"C31"
$SEC"1"
CDS_SEC"1"
MATERIAL"X7R"
PART_NUMBER"CH4104K1B00"
PACK_TYPE"0402"
VOLTAGE"25V"
VALUE"0.1UF"
TOLERANCE"10%"
CDS_LIB"pure_quanta";
"B"
$PN"2"3;
"A"
$PN"1"26;
%"LSF0204DRUTR"
"1","(-2350,1150)","0","pure_quanta","I111";
;
LOCATION"U4"
$SEC"1"
CDS_SEC"1"
PART_NUMBER"AL000204002"
VALUE"LSF0204DRUTR"
MATERIAL"IC"
PART_TYPE"SMLF"
CDS_LIB"pure_quanta"
CDS_LMAN_SYM_OUTLINE"-225,225,225,-225"
NEEDS_NO_SIZE"TRUE";
"EN# \B"
$PN"12"38;
"GND"
$PN"6"2;
"VREF_B"
$PN"11"22;
"VREF_A"
$PN"1"26;
"B4"
$PN"7"61;
"B3"
$PN"8"47;
"B2"
$PN"9"60;
"B1"
$PN"10"59;
"A4"
$PN"5"36;
"A3"
$PN"4"35;
"A2"
$PN"3"34;
"A1"
$PN"2"33;
%"UNIVERSAL_POWER"
"1","(-1750,2550)","0","pure_quanta_power","I139";
;
HDL_POWER"P3V3"
CDS_LIB"pure_quanta_power";
"A"23;
%"Q_RES"
"1","(-1525,2300)","0","pure_quanta","I140";
;
LOCATION"R52"
$SEC"1"
CDS_SEC"1"
VALUE"4.7K"
PACK_TYPE"0402LF"
PART_NUMBER"TMP_QCS24702JB38"
TOLERANCE"5%"
MATERIAL"CHIP"
WATTAGE"1/16W"
CDS_LIB"pure_quanta";
"B"
$PN"2"49;
"A"
$PN"1"23;
%"Q_RES"
"1","(-1525,2250)","0","pure_quanta","I141";
;
LOCATION"R53"
$SEC"1"
CDS_SEC"1"
VALUE"4.7K"
PACK_TYPE"0402LF"
PART_NUMBER"TMP_QCS24702JB38"
TOLERANCE"5%"
MATERIAL"CHIP"
WATTAGE"1/16W"
CDS_LIB"pure_quanta";
"B"
$PN"2"62;
"A"
$PN"1"23;
%"Q_RES"
"1","(-1525,2150)","0","pure_quanta","I142";
;
LOCATION"R55"
$SEC"1"
CDS_SEC"1"
VALUE"4.7K"
PACK_TYPE"0402LF"
PART_NUMBER"TMP_QCS24702JB38"
TOLERANCE"5%"
MATERIAL"CHIP"
WATTAGE"1/16W"
CDS_LIB"pure_quanta";
"B"
$PN"2"48;
"A"
$PN"1"23;
%"Q_RES"
"1","(-1525,2200)","0","pure_quanta","I143";
;
LOCATION"R54"
$SEC"1"
CDS_SEC"1"
VALUE"4.7K"
PACK_TYPE"0402LF"
PART_NUMBER"TMP_QCS24702JB38"
TOLERANCE"5%"
MATERIAL"CHIP"
WATTAGE"1/16W"
CDS_LIB"pure_quanta";
"B"
$PN"2"37;
"A"
$PN"1"23;
%"Q_RES"
"1","(-1575,2800)","0","pure_quanta","I152";
;
LOCATION"R44"
$SEC"1"
CDS_SEC"1"
VALUE"4.7K"
PACK_TYPE"0402LF"
PART_NUMBER"TMP_QCS24702JB38"
TOLERANCE"5%"
MATERIAL"CHIP"
WATTAGE"1/16W"
CDS_LIB"pure_quanta";
"B"
$PN"2"64;
"A"
$PN"1"25;
%"Q_RES"
"1","(-1575,2850)","0","pure_quanta","I153";
;
LOCATION"R43"
$SEC"1"
CDS_SEC"1"
VALUE"4.7K"
PACK_TYPE"0402LF"
PART_NUMBER"TMP_QCS24702JB38"
TOLERANCE"5%"
MATERIAL"CHIP"
WATTAGE"1/16W"
CDS_LIB"pure_quanta";
"B"
$PN"2"63;
"A"
$PN"1"25;
%"Q_RES"
"1","(-1575,2900)","0","pure_quanta","I154";
;
LOCATION"R26"
$SEC"1"
CDS_SEC"1"
VALUE"4.7K"
PACK_TYPE"0402LF"
PART_NUMBER"TMP_QCS24702JB38"
TOLERANCE"5%"
MATERIAL"CHIP"
WATTAGE"1/16W"
CDS_LIB"pure_quanta";
"B"
$PN"2"65;
"A"
$PN"1"25;
%"Q_RES"
"1","(-1575,2750)","0","pure_quanta","I155";
;
LOCATION"R45"
$SEC"1"
CDS_SEC"1"
VALUE"4.7K"
PACK_TYPE"0402LF"
PART_NUMBER"TMP_QCS24702JB38"
TOLERANCE"5%"
MATERIAL"CHIP"
WATTAGE"1/16W"
CDS_LIB"pure_quanta";
"B"
$PN"2"66;
"A"
$PN"1"25;
%"Q_RES"
"1","(-4850,4775)","0","pure_quanta","I162";
;
LOCATION"R1229"
$SEC"1"
CDS_SEC"1"
VALUE"0"
WATTAGE"1/16W"
MATERIAL"CHIP"
TOLERANCE"5%"
PART_NUMBER"CS00002JB38"
PACK_TYPE"0402LF"
CDS_LIB"pure_quanta";
"B"
$PN"2"41;
"A"
$PN"1"52;
%"UNIVERSAL_GND"
"1","(-1225,4200)","0","pure_quanta_power","I166";
;
HDL_POWER"GND"
CDS_LIB"pure_quanta_power";
"A"24;
%"Q_RES"
"1","(-1700,4675)","0","pure_quanta","I167";
;
LOCATION"R1230"
$SEC"1"
CDS_SEC"1"
VALUE"0"
PACK_TYPE"0402LF"
PART_NUMBER"CS00002JB38"
TOLERANCE"5%"
MATERIAL"CHIP"
WATTAGE"1/16W"
CDS_LIB"pure_quanta";
"B"
$PN"2"73;
"A"
$PN"1"71;
%"Q_RES"
"2","(-6850,3575)","0","pure_quanta","I174";
;
LOCATION"R1228"
$SEC"1"
CDS_SEC"1"
PACK_TYPE"0402LF"
VALUE"4.7K"
TOLERANCE"1%"
MATERIAL"EMPTY"
WATTAGE"1/16W"
PART_NUMBER"CS24702FB10"
CDS_LIB"pure_quanta";
"A"
$PN"1"4;
"B"
$PN"2"51;
%"UNIVERSAL_POWER"
"1","(-6850,3800)","0","pure_quanta_power","I175";
;
HDL_POWER"P3V3"
CDS_LIB"pure_quanta_power";
"A"4;
%"UNIVERSAL_GND"
"1","(-6850,2950)","0","pure_quanta_power","I176";
;
HDL_POWER"GND"
CDS_LIB"pure_quanta_power";
"A"5;
%"Q_RES"
"1","(-1675,4475)","0","pure_quanta","I178";
;
LOCATION"R1232"
$SEC"1"
CDS_SEC"1"
VALUE"100"
MATERIAL"EMPTY"
PACK_TYPE"0402LF"
PART_NUMBER"TMP_QCS11002FB22"
TOLERANCE"1%"
WATTAGE"1/16W"
CDS_LIB"pure_quanta";
"B"
$PN"2"24;
"A"
$PN"1"46;
%"Q_RES"
"1","(-1675,4375)","0","pure_quanta","I179";
;
LOCATION"R1233"
$SEC"1"
CDS_SEC"1"
VALUE"100"
MATERIAL"EMPTY"
PACK_TYPE"0402LF"
PART_NUMBER"TMP_QCS11002FB22"
TOLERANCE"1%"
WATTAGE"1/16W"
CDS_LIB"pure_quanta";
"B"
$PN"2"24;
"A"
$PN"1"71;
%"Q_RES"
"1","(-1700,4725)","0","pure_quanta","I181";
;
LOCATION"R1260"
$SEC"1"
CDS_SEC"1"
VALUE"0"
PACK_TYPE"0402LF"
PART_NUMBER"CS00002JB38"
TOLERANCE"5%"
MATERIAL"CHIP"
WATTAGE"1/16W"
CDS_LIB"pure_quanta";
"B"
$PN"2"72;
"A"
$PN"1"46;
%"Q_RES"
"2","(-6850,3175)","0","pure_quanta","I182";
;
LOCATION"R1259"
$SEC"1"
CDS_SEC"1"
PACK_TYPE"0402LF"
VALUE"4.7K"
TOLERANCE"1%"
MATERIAL"EMPTY"
WATTAGE"1/16W"
PART_NUMBER"CS24702FB10"
CDS_LIB"pure_quanta";
"A"
$PN"1"51;
"B"
$PN"2"5;
%"VCC_CORE"
"1","(-1775,3150)","0","pure_quanta_power","I183";
;
HDL_POWER"PVDD11_S3_P0"
CDS_LIB"pure_quanta_power";
"A"25;
%"VCC_CORE"
"1","(-2875,1800)","0","pure_quanta_power","I184";
;
HDL_POWER"PVDD11_S3_P0"
CDS_LIB"pure_quanta_power";
"A"26;
%"Q_RES"
"2","(-3100,2875)","0","pure_quanta","I187";
;
LOCATION"R1417"
$SEC"1"
CDS_SEC"1"
VALUE"4.7K"
PACK_TYPE"0402LF"
MATERIAL"CHIP"
WATTAGE"1/16W"
TOLERANCE"5%"
PART_NUMBER"TMP_QCS24702JB38"
CDS_LIB"pure_quanta";
"A"
$PN"1"7;
"B"
$PN"2"39;
%"UNIVERSAL_GND"
"1","(-3100,2000)","2","pure_quanta_power","I188";
;
HDL_POWER"GND"
CDS_LIB"pure_quanta_power";
"A"6;
%"MOSFET_N_GSD"
"1","(-3125,2350)","0","pure_quanta","I189";
;
LOCATION"Q15"
$SEC"1"
CDS_SEC"1"
PART_TYPE"SMLF"
MATERIAL"IC"
PART_NUMBER"BAM01380023"
VALUE"NX138BK"
CDS_LIB"pure_quanta"
CDS_LMAN_SYM_OUTLINE"-100,100,100,-100"
NEEDS_NO_SIZE"TRUE";
"DRAIN"
$PN"D"39;
"SOURCE"
$PN"S"6;
"GATE"
$PN"G"40;
%"VCC_CORE"
"1","(-3100,3075)","0","pure_quanta_power","I191";
;
HDL_POWER"PVDD11_S3_P0"
CDS_LIB"pure_quanta_power";
"A"7;
%"Q_RES"
"1","(-2400,2675)","0","pure_quanta","I193";
;
LOCATION"R5000"
$SEC"1"
CDS_SEC"1"
VALUE"0"
CDS_LIB"pure_quanta"
WATTAGE"1/16W"
MATERIAL"CHIP"
TOLERANCE"5%"
PART_NUMBER"CS00002JB38"
PACK_TYPE"0402LF";
"B"
$PN"2"21;
"A"
$PN"1"39;
%"VCC_CORE"
"1","(-4625,5575)","0","pure_quanta_power","I2";
;
HDL_POWER"P3V3_9ZX_VDDA_2"
ROOM"DB2000_1_BCLK"
VOLTAGE"3.3"
CDS_LIB"pure_quanta_power"
BOM_COST"SYS_CLOCK";
"A"27;
%"UNIVERSAL_POWER"
"1","(-4225,5950)","0","pure_quanta_power","I3";
;
HDL_POWER"P3V3_9ZX_VDD_2"
ROOM"DB2000_1_BCLK"
VOLTAGE"3.3"
BOM_COST"SYS_CLOCK"
CDS_LIB"pure_quanta_power";
"A"28;
%"VCC_CORE"
"1","(-2625,5950)","0","pure_quanta_power","I4";
;
HDL_POWER"P3V3_9ZX_VDDA_2"
ROOM"DB2000_1_BCLK"
VOLTAGE"3.3"
BOM_COST"SYS_CLOCK"
CDS_LIB"pure_quanta_power";
"A"29;
%"VCC_CORE"
"1","(-6250,5675)","0","mstr_symbols","I40";
;
HDL_POWER"P3V3_9ZX_VDDA_2"
ROOM"DB2000_1_BCLK"
VOLTAGE"3.3"
BOM_COST"SYS_CLOCK"
CDS_LIB"mstr_symbols";
"A"30;
%"Q_CAP"
"1","(-6250,5325)","0","pure_quanta","I41";
;
LOCATION"C1234"
$SEC"1"
CDS_SEC"1"
PACK_TYPE"0402"
VOLTAGE"25V"
VALUE"0.1UF"
TOLERANCE"10%"
MATERIAL"X7R"
PART_NUMBER"CH4104K1B00"
CDS_LIB"pure_quanta";
"B"
$PN"2"8;
"A"
$PN"1"30;
%"Q_CAP"
"1","(-6450,5325)","0","pure_quanta","I42";
;
LOCATION"C1233"
$SEC"1"
CDS_SEC"1"
PACK_TYPE"0402"
VOLTAGE"25V"
VALUE"0.1UF"
TOLERANCE"10%"
MATERIAL"X7R"
PART_NUMBER"CH4104K1B00"
CDS_LIB"pure_quanta";
"B"
$PN"2"9;
"A"
$PN"1"30;
%"Q_CAP"
"1","(-6700,5325)","0","pure_quanta","I43";
;
LOCATION"C1232"
$SEC"1"
CDS_SEC"1"
PACK_TYPE"C0402"
VOLTAGE"25V"
VALUE"1UF"
TOLERANCE"10%"
MATERIAL"X6S"
PART_NUMBER"CH5104KEB02"
CDS_LIB"pure_quanta";
"B"
$PN"2"10;
"A"
$PN"1"30;
%"Q_RES"
"1","(-7200,5475)","0","pure_quanta","I44";
;
LOCATION"R796"
$SEC"1"
CDS_SEC"1"
PACK_TYPE"0603LF"
VALUE"1"
TOLERANCE"1%"
MATERIAL"CHIP"
WATTAGE"1/10W"
PART_NUMBER"CS-1003F920"
CDS_LIB"pure_quanta";
"B"
$PN"2"30;
"A"
$PN"1"31;
%"UNIVERSAL_GND"
"1","(-6250,5050)","0","pure_quanta_power","I45";
;
HDL_POWER"GND"
CDS_LIB"pure_quanta_power";
"A"8;
%"UNIVERSAL_GND"
"1","(-6450,5050)","0","pure_quanta_power","I46";
;
HDL_POWER"GND"
CDS_LIB"pure_quanta_power";
"A"9;
%"UNIVERSAL_GND"
"1","(-6700,5050)","0","pure_quanta_power","I47";
;
HDL_POWER"GND"
CDS_LIB"pure_quanta_power";
"A"10;
%"Q_CAP"
"1","(-7365,4790)","0","pure_quanta","I49";
;
LOCATION"C1230"
$SEC"1"
CDS_SEC"1"
PACK_TYPE"0402"
VOLTAGE"25V"
VALUE"0.1UF"
TOLERANCE"10%"
MATERIAL"X7R"
PART_NUMBER"CH4104K1B00"
CDS_LIB"pure_quanta";
"B"
$PN"2"11;
"A"
$PN"1"31;
%"UNIVERSAL_GND"
"1","(-7365,4515)","0","pure_quanta_power","I51";
;
HDL_POWER"GND"
CDS_LIB"pure_quanta_power";
"A"11;
%"UNIVERSAL_POWER"
"1","(-7550,5675)","0","mstr_symbols","I52";
;
HDL_POWER"P3V3_9ZX_VDD_2"
ROOM"DB2000_1_BCLK"
VOLTAGE"3.3"
CDS_LIB"mstr_symbols"
BOM_COST"SYS_CLOCK";
"A"31;
%"UNIVERSAL_POWER"
"1","(-9225,5625)","0","pure_quanta_power","I57";
;
HDL_POWER"P3V3"
CDS_LIB"pure_quanta_power";
"A"32;
%"Q_INDUCTOR"
"1","(-8875,5500)","0","pure_quanta","I58";
;
LOCATION"L8"
$SEC"1"
CDS_SEC"1"
PACK_TYPE"SMLF"
PART_NUMBER"CX12S331000"
VALUE"330/2.5A"
MATERIAL"IND"
CDS_LIB"pure_quanta"
NEEDS_NO_SIZE"TRUE";
"1"
$PN"1"32;
"2"
$PN"2"31;
%"Q_CAP"
"1","(-7595,4795)","0","pure_quanta","I59";
;
LOCATION"C1229"
$SEC"1"
CDS_SEC"1"
PACK_TYPE"0402"
VOLTAGE"25V"
VALUE"0.1UF"
TOLERANCE"10%"
MATERIAL"X7R"
PART_NUMBER"CH4104K1B00"
CDS_LIB"pure_quanta";
"B"
$PN"2"12;
"A"
$PN"1"31;
%"Q_CAP"
"1","(-7825,4800)","0","pure_quanta","I61";
;
LOCATION"C1228"
$SEC"1"
CDS_SEC"1"
PACK_TYPE"0402"
VOLTAGE"25V"
VALUE"0.1UF"
TOLERANCE"10%"
MATERIAL"X7R"
PART_NUMBER"CH4104K1B00"
CDS_LIB"pure_quanta";
"B"
$PN"2"13;
"A"
$PN"1"31;
%"UNIVERSAL_GND"
"1","(-7595,4520)","0","pure_quanta_power","I62";
;
HDL_POWER"GND"
CDS_LIB"pure_quanta_power";
"A"12;
%"UNIVERSAL_GND"
"1","(-7825,4525)","0","pure_quanta_power","I63";
;
HDL_POWER"GND"
CDS_LIB"pure_quanta_power";
"A"13;
%"Q_CAP"
"1","(-8050,4800)","0","pure_quanta","I65";
;
LOCATION"C1226"
$SEC"1"
CDS_SEC"1"
PACK_TYPE"0402"
VOLTAGE"25V"
VALUE"0.1UF"
TOLERANCE"10%"
MATERIAL"X7R"
PART_NUMBER"CH4104K1B00"
CDS_LIB"pure_quanta";
"B"
$PN"2"14;
"A"
$PN"1"31;
%"Q_CAP"
"1","(-8300,4800)","0","pure_quanta","I67";
;
LOCATION"C1224"
$SEC"1"
CDS_SEC"1"
PACK_TYPE"0402"
VOLTAGE"25V"
VALUE"0.1UF"
TOLERANCE"10%"
MATERIAL"X7R"
PART_NUMBER"CH4104K1B00"
CDS_LIB"pure_quanta";
"B"
$PN"2"15;
"A"
$PN"1"31;
%"UNIVERSAL_GND"
"1","(-8050,4525)","0","pure_quanta_power","I68";
;
HDL_POWER"GND"
CDS_LIB"pure_quanta_power";
"A"14;
%"UNIVERSAL_GND"
"1","(-8300,4525)","0","pure_quanta_power","I69";
;
HDL_POWER"GND"
CDS_LIB"pure_quanta_power";
"A"15;
%"Q_CAP"
"1","(-8700,4835)","0","pure_quanta","I71";
;
LOCATION"C1221"
$SEC"1"
CDS_SEC"1"
PACK_TYPE"C0402"
VOLTAGE"25V"
VALUE"1UF"
TOLERANCE"10%"
MATERIAL"X6S"
PART_NUMBER"CH5104KEB02"
CDS_LIB"pure_quanta";
"B"
$PN"2"16;
"A"
$PN"1"31;
%"UNIVERSAL_GND"
"1","(-8700,4550)","0","pure_quanta_power","I72";
;
HDL_POWER"GND"
CDS_LIB"pure_quanta_power";
"A"16;
%"Q_RES"
"1","(-1700,5275)","0","pure_quanta","I79";
;
LOCATION"R2292"
$SEC"1"
CDS_SEC"1"
VALUE"0"
PACK_TYPE"0402LF"
PART_NUMBER"CS00002JB38"
TOLERANCE"5%"
MATERIAL"CHIP"
WATTAGE"1/16W"
CDS_LIB"pure_quanta";
"B"
$PN"2"74;
"A"
$PN"1"45;
%"Q_RES"
"1","(-1700,5225)","0","pure_quanta","I80";
;
LOCATION"R2293"
$SEC"1"
CDS_SEC"1"
VALUE"0"
PACK_TYPE"0402LF"
PART_NUMBER"CS00002JB38"
TOLERANCE"5%"
MATERIAL"CHIP"
WATTAGE"1/16W"
CDS_LIB"pure_quanta";
"B"
$PN"2"75;
"A"
$PN"1"68;
%"Q_RES"
"1","(-1700,5175)","0","pure_quanta","I81";
;
LOCATION"R2294"
$SEC"1"
CDS_SEC"1"
VALUE"0"
PACK_TYPE"0402LF"
PART_NUMBER"CS00002JB38"
TOLERANCE"5%"
MATERIAL"CHIP"
WATTAGE"1/16W"
CDS_LIB"pure_quanta";
"B"
$PN"2"43;
"A"
$PN"1"70;
%"Q_RES"
"1","(-1700,5125)","0","pure_quanta","I82";
;
LOCATION"R2295"
$SEC"1"
CDS_SEC"1"
VALUE"0"
PACK_TYPE"0402LF"
PART_NUMBER"CS00002JB38"
TOLERANCE"5%"
MATERIAL"CHIP"
WATTAGE"1/16W"
CDS_LIB"pure_quanta";
"B"
$PN"2"44;
"A"
$PN"1"69;
%"UNIVERSAL_GND"
"1","(-1900,5425)","0","pure_quanta_power","I85";
;
HDL_POWER"GND"
CDS_LIB"pure_quanta_power";
"A"76;
%"UNIVERSAL_POWER"
"1","(-1900,6125)","0","pure_quanta_power","I86";
;
HDL_POWER"P3V3"
CDS_LIB"pure_quanta_power";
"A"17;
%"Q_RES"
"2","(-1900,5575)","0","pure_quanta","I87";
;
LOCATION"R122"
$SEC"1"
CDS_SEC"1"
WATTAGE"1/16W"
PACK_TYPE"0402LF"
VALUE"10K"
TOLERANCE"5%"
MATERIAL"CHIP"
PART_NUMBER"TMP_QCS31002JB28"
CDS_LIB"pure_quanta";
"A"
$PN"1"67;
"B"
$PN"2"76;
%"Q_RES"
"2","(-1900,5925)","0","pure_quanta","I88";
;
LOCATION"R121"
$SEC"1"
CDS_SEC"1"
PACK_TYPE"0402LF"
VALUE"10K"
TOLERANCE"5%"
MATERIAL"CHIP"
WATTAGE"1/16W"
PART_NUMBER"TMP_QCS31002JB28"
CDS_LIB"pure_quanta";
"A"
$PN"1"17;
"B"
$PN"2"67;
%"UNIVERSAL_GND"
"1","(-2650,4200)","0","pure_quanta_power","I89";
;
HDL_POWER"GND"
CDS_LIB"pure_quanta_power";
"A"18;
%"UNIVERSAL_GND"
"1","(-8475,2925)","0","pure_quanta_power","I90";
;
HDL_POWER"GND"
CDS_LIB"pure_quanta_power";
"A"19;
%"UNIVERSAL_POWER"
"1","(-8475,3775)","0","pure_quanta_power","I91";
;
HDL_POWER"P3V3"
CDS_LIB"pure_quanta_power";
"A"20;
%"Q_RES"
"2","(-8475,3525)","0","pure_quanta","I92";
;
LOCATION"R595"
$SEC"1"
CDS_SEC"1"
PACK_TYPE"0402LF"
VALUE"1K"
TOLERANCE"5%"
MATERIAL"EMPTY"
WATTAGE"1/16W"
PART_NUMBER"TMP_QCS21002JB34"
CDS_LIB"pure_quanta";
"A"
$PN"1"20;
"B"
$PN"2"50;
%"Q_RES"
"2","(-8475,3100)","0","pure_quanta","I93";
;
LOCATION"R596"
$SEC"1"
CDS_SEC"1"
PACK_TYPE"0402LF"
VALUE"1K"
TOLERANCE"5%"
MATERIAL"CHIP"
WATTAGE"1/16W"
PART_NUMBER"TMP_QCS21002JB34"
CDS_LIB"pure_quanta";
"A"
$PN"1"50;
"B"
$PN"2"19;
%"Q_RES"
"1","(-4850,4875)","0","pure_quanta","I97";
;
LOCATION"R626"
$SEC"1"
CDS_SEC"1"
VALUE"0"
PACK_TYPE"0402LF"
PART_NUMBER"CS00002JB38"
TOLERANCE"5%"
MATERIAL"CHIP"
WATTAGE"1/16W"
CDS_LIB"pure_quanta";
"B"
$PN"2"55;
"A"
$PN"1"53;
%"Q_RES"
"1","(-4850,4925)","0","pure_quanta","I98";
;
LOCATION"R625"
$SEC"1"
CDS_SEC"1"
VALUE"0"
PACK_TYPE"0402LF"
PART_NUMBER"CS00002JB38"
TOLERANCE"5%"
MATERIAL"CHIP"
WATTAGE"1/16W"
CDS_LIB"pure_quanta";
"B"
$PN"2"56;
"A"
$PN"1"54;
END.
